# TIMECARD (Time Appliance Project (Time Card)) — schematic netlist excerpt (pin names and nets, part order shuffled) for the footprints in the layout excerpt that follows; sources: Cadence DE-HDL packaged netlist, KiCad conversion of R4006-B0001-02_R01.brd

R233  RESISTOR  2.1KOHM 1%  pkg SMC_0402R  page 31 : \1\ = SG ; \2\ = UNNAMED_515_ISL80101IRAJZDFN10_
C205  CAPACITOR  0.1UF 10V 10%  pkg SMC_0402R_H022  page 14 : \1\ = FPGA_MGTAVTT ; \2\ = SG

(kicad_pcb
	(version 20260206)
	(generator "pcbnew")
	(generator_version "10.0")
	(general
		(thickness 1.6)
		(legacy_teardrops no)
	)
	(paper "A4")
	(title_block
		(title "timecard-production-celestica-r4006 — R4006-B0001-02_R01.brd")
		(comment 1 "Time Appliance Project (Time Card) / footprints 677-678 of 1113")
	)
	(layers
		(0 "F.Cu" signal "TOP")
		(4 "In1.Cu" signal "L02_GND1")
		(6 "In2.Cu" signal "L03_SIG1")
		(8 "In3.Cu" signal "L04_GND2")
		(10 "In4.Cu" signal "L05_VCC1")
		(12 "In5.Cu" signal "L06_VCC2")
		(14 "In6.Cu" signal "L07_GND3")
		(16 "In7.Cu" signal "L08_SIG2")
		(18 "In8.Cu" signal "L09_GND4")
		(2 "B.Cu" signal "BOTTOM")
		(9 "F.Adhes" user "F.Adhesive")
		(11 "B.Adhes" user "B.Adhesive")
		(13 "F.Paste" user "Package Geometry/Pastemask Top")
		(15 "B.Paste" user "Package Geometry/Pastemask Bottom")
		(5 "F.SilkS" user "Ref Des/Silkscreen Top")
		(7 "B.SilkS" user "Ref Des/Silkscreen Bottom")
		(1 "F.Mask" user "Board Geometry/Soldermask Top")
		(3 "B.Mask" user "Board Geometry/Soldermask Bottom")
		(17 "Dwgs.User" user "User.Drawings")
		(19 "Cmts.User" user "User.Comments")
		(21 "Eco1.User" user "User.Eco1")
		(23 "Eco2.User" user "User.Eco2")
		(25 "Edge.Cuts" user "Board Geometry/Outline")
		(27 "Margin" user)
		(31 "F.CrtYd" user "Package Geometry/Place Bound Top")
		(29 "B.CrtYd" user "Package Geometry/Place Bound Bottom")
		(35 "F.Fab" user "Ref Des/Assembly Top")
		(33 "B.Fab" user "Ref Des/Assembly Bottom")
	)
	(footprint ""
		(layer "B.Cu")
		(at 99.846892 -44.323254 -90)
		(property "Reference" "C205"
			(at -0.634746 -0.959358 270)
			(unlocked yes)
			(layer "B.SilkS")
			(effects
				(font
					(size 0.635 0.4064)
					(thickness 0.1524)
				)
				(justify mirror)
			)
		)
		(property "Value" "VAL*"
			(at 0 3.718306 270)
			(unlocked yes)
			(layer "B.Fab")
			(hide yes)
			(effects
				(font
					(size 0.7874 0.5842)
					(thickness 0.127)
				)
				(justify mirror)
			)
		)
		(property "Tolerance" "TOL*"
			(at 0 4.861306 270)
			(unlocked yes)
			(layer "Cmts.User")
			(hide yes)
			(effects
				(font
					(size 0.7874 0.5842)
					(thickness 0.127)
				)
				(justify mirror)
			)
		)
		(property "User Part Number" "PARTNUM*"
			(at 0 2.575306 270)
			(unlocked yes)
			(layer "Cmts.User")
			(hide yes)
			(effects
				(font
					(size 0.7874 0.5842)
					(thickness 0.127)
				)
				(justify mirror)
			)
		)
		(property "Device Type" "CAPACITOR-G105-0B104-CK,0.1UF,A"
			(at 0 1.432306 270)
			(unlocked yes)
			(layer "B.Fab")
			(hide yes)
			(effects
				(font
					(size 0.7874 0.5842)
					(thickness 0.127)
				)
				(justify mirror)
			)
		)
		(duplicate_pad_numbers_are_jumpers no)
		(fp_line
			(start -0.970026 0.4699)
			(end 0.970026 0.4699)
			(stroke
				(width 0.1)
				(type default)
			)
			(layer "B.SilkS")
		)
		(fp_line
			(start 0.970026 0.4699)
			(end 0.970026 -0.4699)
			(stroke
				(width 0.1)
				(type default)
			)
			(layer "B.SilkS")
		)
		(fp_line
			(start -0.970026 -0.4699)
			(end -0.970026 0.4699)
			(stroke
				(width 0.1)
				(type default)
			)
			(layer "B.SilkS")
		)
		(fp_line
			(start 0.970026 -0.4699)
			(end -0.970026 -0.4699)
			(stroke
				(width 0.1)
				(type default)
			)
			(layer "B.SilkS")
		)
		(fp_poly
			(pts
				(xy 0.970026 0.4699) (xy -0.970026 0.4699) (xy -0.970026 -0.4699) (xy 0.970026 -0.4699)
			)
			(stroke
				(width 0)
				(type default)
			)
			(fill no)
			(layer "B.CrtYd")
		)
		(fp_line
			(start -0.508 0.3048)
			(end 0.508 0.3048)
			(stroke
				(width 0.1)
				(type default)
			)
			(layer "B.Fab")
		)
		(fp_line
			(start 0.508 0.3048)
			(end 0.508 -0.3048)
			(stroke
				(width 0.1)
				(type default)
			)
			(layer "B.Fab")
		)
		(fp_line
			(start -0.508 -0.3048)
			(end -0.508 0.3048)
			(stroke
				(width 0.1)
				(type default)
			)
			(layer "B.Fab")
		)
		(fp_line
			(start 0.508 -0.3048)
			(end -0.508 -0.3048)
			(stroke
				(width 0.1)
				(type default)
			)
			(layer "B.Fab")
		)
		(pad "1" smd circle
			(at 0.500126 0 90)
			(size 0.635 0.635)
			(layers "B.Cu" "B.Mask" "B.Paste")
			(net "FPGA_MGTAVTT")
		)
		(pad "2" smd circle
			(at -0.500126 0 90)
			(size 0.635 0.635)
			(layers "B.Cu" "B.Mask" "B.Paste")
			(net "SG")
		)
	)
	(footprint ""
		(layer "B.Cu")
		(at 137.795 -17.526 180)
		(property "Reference" "R233"
			(at 1.27 1.10363 0)
			(unlocked yes)
			(layer "B.SilkS")
			(effects
				(font
					(size 0.7874 0.5842)
					(thickness 0.1524)
				)
				(justify mirror)
			)
		)
		(property "Value" "VAL*"
			(at -0.0508 2.245106 180)
			(unlocked yes)
			(layer "B.Fab")
			(hide yes)
			(effects
				(font
					(size 0.7874 0.5842)
					(thickness 0.1524)
				)
				(justify mirror)
			)
		)
		(property "Tolerance" "TOL*"
			(at -0.0508 3.261106 180)
			(unlocked yes)
			(layer "Cmts.User")
			(hide yes)
			(effects
				(font
					(size 0.7874 0.5842)
					(thickness 0.1524)
				)
				(justify mirror)
			)
		)
		(property "Device Type" "RESISTOR-G155-02101-01,2.1KOHMA"
			(at -0.0762 1.254506 180)
			(unlocked yes)
			(layer "B.Fab")
			(hide yes)
			(effects
				(font
					(size 0.7874 0.5842)
					(thickness 0.1524)
				)
				(justify mirror)
			)
		)
		(property "User Part Number" "PARTNUM*"
			(at -0.0762 4.302506 180)
			(unlocked yes)
			(layer "Cmts.User")
			(hide yes)
			(effects
				(font
					(size 0.7874 0.5842)
					(thickness 0.1524)
				)
				(justify mirror)
			)
		)
		(duplicate_pad_numbers_are_jumpers no)
		(fp_line
			(start 1.143 0.5588)
			(end -1.143 0.5588)
			(stroke
				(width 0.1)
				(type default)
			)
			(layer "B.SilkS")
		)
		(fp_line
			(start 1.143 -0.5588)
			(end 1.143 0.5588)
			(stroke
				(width 0.1)
				(type default)
			)
			(layer "B.SilkS")
		)
		(fp_line
			(start -1.143 0.5588)
			(end -1.143 -0.5588)
			(stroke
				(width 0.1)
				(type default)
			)
			(layer "B.SilkS")
		)
		(fp_line
			(start -1.143 -0.5588)
			(end 1.143 -0.5588)
			(stroke
				(width 0.1)
				(type default)
			)
			(layer "B.SilkS")
		)
		(fp_rect
			(start 1.143 -0.5588)
			(end -1.143 0.5588)
			(stroke
				(width 0)
				(type default)
			)
			(fill no)
			(layer "B.CrtYd")
		)
		(fp_line
			(start 0.508 0.3048)
			(end -0.508 0.3048)
			(stroke
				(width 0.1)
				(type default)
			)
			(layer "B.Fab")
		)
		(fp_line
			(start 0.508 -0.3048)
			(end 0.508 0.3048)
			(stroke
				(width 0.1)
				(type default)
			)
			(layer "B.Fab")
		)
		(fp_line
			(start -0.508 0.3048)
			(end -0.508 -0.3048)
			(stroke
				(width 0.1)
				(type default)
			)
			(layer "B.Fab")
		)
		(fp_line
			(start -0.508 -0.3048)
			(end 0.508 -0.3048)
			(stroke
				(width 0.1)
				(type default)
			)
			(layer "B.Fab")
		)
		(pad "1" smd rect
			(at 0.5334 0)
			(size 0.7112 0.6096)
			(layers "B.Cu" "B.Mask" "B.Paste")
			(net "SG")
		)
		(pad "2" smd rect
			(at -0.5334 0)
			(size 0.7112 0.6096)
			(layers "B.Cu" "B.Mask" "B.Paste")
			(net "UNNAMED_515_ISL80101IRAJZDFN10_")
		)
		(zone
			(layer "B.Cu")
			(hatch none 0.5)
			(connect_pads
				(clearance 0)
			)
			(min_thickness 0.25)
			(keepout
				(tracks allowed)
				(vias not_allowed)
				(pads allowed)
				(copperpour not_allowed)
				(footprints allowed)
			)
			(placement
				(enabled no)
				(sheetname "")
			)
			(fill
				(thermal_gap 0.5)
				(thermal_bridge_width 0.5)
				(island_removal_mode 0)
			)
			(polygon
				(pts
					(xy 137.7188 -17.2212) (xy 137.8712 -17.2212) (xy 137.8712 -17.8308) (xy 137.7188 -17.8308)
				)
			)
		)
	)
)
